(kicad_pcb
	(version 20260206)
	(generator "pcbnew")
	(generator_version "10.0")
	(general
		(thickness 1.6)
		(legacy_teardrops no)
	)
	(paper "A4")
	(title_block
		(title "fcb — Lightning_FCB_BRD.brd")
		(comment 1 "Lightning (Wiwynn / Facebook NVMe JBOF) / footprints 462-468 of 495")
	)
	(layers
		(0 "F.Cu" signal "TOP")
		(4 "In1.Cu" signal "L2GND")
		(6 "In2.Cu" signal "L3VCC")
		(2 "B.Cu" signal "BOTTOM")
		(9 "F.Adhes" user "F.Adhesive")
		(11 "B.Adhes" user "B.Adhesive")
		(13 "F.Paste" user "Package Geometry/Pastemask Top")
		(15 "B.Paste" user "Package Geometry/Pastemask Bottom")
		(5 "F.SilkS" user "Ref Des/Silkscreen Top")
		(7 "B.SilkS" user "Ref Des/Silkscreen Bottom")
		(1 "F.Mask" user "Board Geometry/Soldermask Top")
		(3 "B.Mask" user "Board Geometry/Soldermask Bottom")
		(17 "Dwgs.User" user "User.Drawings")
		(19 "Cmts.User" user "User.Comments")
		(21 "Eco1.User" user "User.Eco1")
		(23 "Eco2.User" user "User.Eco2")
		(25 "Edge.Cuts" user "Board Geometry/Outline")
		(27 "Margin" user)
		(31 "F.CrtYd" user "Package Geometry/Place Bound Top")
		(29 "B.CrtYd" user "Package Geometry/Place Bound Bottom")
		(35 "F.Fab" user "Ref Des/Assembly Top")
		(33 "B.Fab" user "Ref Des/Assembly Bottom")
	)
	(footprint ""
		(layer "F.Cu")
		(at 37.17671 -154.818334)
		(property "Reference" "C2"
			(at 0 0 0)
			(layer "F.SilkS")
			(hide yes)
			(effects
				(font
					(size 1.27 1.27)
				)
			)
		)
		(property "Value" "SCD1U16V2KX-3GP"
			(at 1.1811 -2.7051 0)
			(unlocked yes)
			(layer "F.Fab")
			(hide yes)
			(effects
				(font
					(size 1.016 1.016)
					(thickness 0.1524)
				)
			)
		)
		(property "Device Type" "C402H22"
			(at 1.1811 -4.2291 0)
			(unlocked yes)
			(layer "F.Fab")
			(hide yes)
			(effects
				(font
					(size 1.016 1.016)
					(thickness 0.1524)
				)
			)
		)
		(duplicate_pad_numbers_are_jumpers no)
		(fp_rect
			(start -0.4318 0.9525)
			(end 0.4318 -0.9525)
			(stroke
				(width 0)
				(type default)
			)
			(fill no)
			(layer "F.CrtYd")
		)
		(fp_rect
			(start -0.4318 0.9525)
			(end 0.4318 -0.9525)
			(stroke
				(width 0)
				(type default)
			)
			(fill no)
			(layer "F.Fab")
		)
		(pad "1" smd custom
			(at 0 -0.4445)
			(size 0.1524 0.1524)
			(layers "F.Cu" "F.Mask" "F.Paste")
			(net "NCT7904_3VDD")
			(options
				(clearance outline)
				(anchor circle)
			)
			(primitives
				(gr_poly
					(pts
						(arc
							(start 0.3048 -0.2032)
							(mid 0.275042 -0.275042)
							(end 0.2032 -0.3048)
						)
						(arc
							(start -0.2032 -0.3048)
							(mid -0.275042 -0.275042)
							(end -0.3048 -0.2032)
						)
						(arc
							(start -0.3048 0.2032)
							(mid -0.275042 0.275042)
							(end -0.2032 0.3048)
						)
						(arc
							(start 0.2032 0.3048)
							(mid 0.275042 0.275042)
							(end 0.3048 0.2032)
						)
					)
					(width 0)
					(fill yes)
				)
			)
		)
		(pad "2" smd custom
			(at 0 0.4445)
			(size 0.1524 0.1524)
			(layers "F.Cu" "F.Mask" "F.Paste")
			(net "GND")
			(options
				(clearance outline)
				(anchor circle)
			)
			(primitives
				(gr_poly
					(pts
						(arc
							(start 0.3048 -0.2032)
							(mid 0.275042 -0.275042)
							(end 0.2032 -0.3048)
						)
						(arc
							(start -0.2032 -0.3048)
							(mid -0.275042 -0.275042)
							(end -0.3048 -0.2032)
						)
						(arc
							(start -0.3048 0.2032)
							(mid -0.275042 0.275042)
							(end -0.2032 0.3048)
						)
						(arc
							(start 0.2032 0.3048)
							(mid 0.275042 0.275042)
							(end 0.3048 0.2032)
						)
					)
					(width 0)
					(fill yes)
				)
			)
		)
	)
	(footprint ""
		(layer "F.Cu")
		(at 17.91589 -175.540924 180)
		(property "Reference" "C10"
			(at 0 0 180)
			(layer "F.SilkS")
			(hide yes)
			(effects
				(font
					(size 1.27 1.27)
				)
			)
		)
		(property "Value" "SCD1U50V3KX-GP"
			(at 0 -2.8194 180)
			(unlocked yes)
			(layer "F.Fab")
			(hide yes)
			(effects
				(font
					(size 1.016 1.016)
					(thickness 0.1524)
				)
			)
		)
		(property "Device Type" "C603H36"
			(at 0 -4.3434 180)
			(unlocked yes)
			(layer "F.Fab")
			(hide yes)
			(effects
				(font
					(size 1.016 1.016)
					(thickness 0.1524)
				)
			)
		)
		(duplicate_pad_numbers_are_jumpers no)
		(fp_line
			(start 0.508 0)
			(end -0.508 0)
			(stroke
				(width 0.2032)
				(type default)
			)
			(layer "F.SilkS")
		)
		(fp_rect
			(start -0.5842 1.3335)
			(end 0.5842 -1.3335)
			(stroke
				(width 0)
				(type default)
			)
			(fill no)
			(layer "F.CrtYd")
		)
		(fp_rect
			(start -0.5842 1.3335)
			(end 0.5842 -1.3335)
			(stroke
				(width 0)
				(type default)
			)
			(fill no)
			(layer "F.Fab")
		)
		(pad "1" smd custom
			(at 0 -0.762 180)
			(size 0.2159 0.2159)
			(layers "F.Cu" "F.Mask" "F.Paste")
			(net "P3V3")
			(options
				(clearance outline)
				(anchor circle)
			)
			(primitives
				(gr_poly
					(pts
						(arc
							(start -0.3302 -0.4318)
							(mid -0.402042 -0.402042)
							(end -0.4318 -0.3302)
						)
						(arc
							(start -0.4318 0.3302)
							(mid -0.402042 0.402042)
							(end -0.3302 0.4318)
						)
						(arc
							(start 0.3302 0.4318)
							(mid 0.402042 0.402042)
							(end 0.4318 0.3302)
						)
						(arc
							(start 0.4318 -0.3302)
							(mid 0.402042 -0.402042)
							(end 0.3302 -0.4318)
						)
					)
					(width 0)
					(fill yes)
				)
			)
		)
		(pad "2" smd custom
			(at 0 0.762 180)
			(size 0.2159 0.2159)
			(layers "F.Cu" "F.Mask" "F.Paste")
			(net "GND")
			(options
				(clearance outline)
				(anchor circle)
			)
			(primitives
				(gr_poly
					(pts
						(arc
							(start -0.3302 -0.4318)
							(mid -0.402042 -0.402042)
							(end -0.4318 -0.3302)
						)
						(arc
							(start -0.4318 0.3302)
							(mid -0.402042 0.402042)
							(end -0.3302 0.4318)
						)
						(arc
							(start 0.3302 0.4318)
							(mid 0.402042 0.402042)
							(end 0.4318 0.3302)
						)
						(arc
							(start 0.4318 -0.3302)
							(mid 0.402042 -0.402042)
							(end 0.3302 -0.4318)
						)
					)
					(width 0)
					(fill yes)
				)
			)
		)
	)
	(footprint ""
		(layer "F.Cu")
		(at 21.6916 -140.4366 180)
		(property "Reference" "PU6"
			(at 0 0 180)
			(layer "F.SilkS")
			(hide yes)
			(effects
				(font
					(size 1.27 1.27)
				)
			)
		)
		(property "Value" "TPS2490DGSR-GP"
			(at 0 -11.1252 180)
			(unlocked yes)
			(layer "F.Fab")
			(hide yes)
			(effects
				(font
					(size 1.016 1.016)
					(thickness 0.1524)
				)
			)
		)
		(property "Device Type" "MSOP10H44"
			(at 0 -12.6492 180)
			(unlocked yes)
			(layer "F.Fab")
			(hide yes)
			(effects
				(font
					(size 1.016 1.016)
					(thickness 0.1524)
				)
			)
		)
		(duplicate_pad_numbers_are_jumpers no)
		(fp_line
			(start 1.143 1.016)
			(end -2.0066 1.016)
			(stroke
				(width 0.1524)
				(type default)
			)
			(layer "F.SilkS")
		)
		(fp_line
			(start 1.143 -1.016)
			(end 1.143 1.016)
			(stroke
				(width 0.1524)
				(type default)
			)
			(layer "F.SilkS")
		)
		(fp_line
			(start -1.5748 0)
			(end -1.9558 0.381)
			(stroke
				(width 0.1524)
				(type default)
			)
			(layer "F.SilkS")
		)
		(fp_line
			(start -1.5748 0)
			(end -1.9558 -0.381)
			(stroke
				(width 0.1524)
				(type default)
			)
			(layer "F.SilkS")
		)
		(fp_line
			(start -1.8288 1.016)
			(end -1.8288 3.048)
			(stroke
				(width 0.508)
				(type default)
			)
			(layer "F.SilkS")
		)
		(fp_line
			(start -2.0066 1.016)
			(end -2.0066 -1.016)
			(stroke
				(width 0.1524)
				(type default)
			)
			(layer "F.SilkS")
		)
		(fp_line
			(start -2.0066 -1.016)
			(end 1.143 -1.016)
			(stroke
				(width 0.1524)
				(type default)
			)
			(layer "F.SilkS")
		)
		(fp_poly
			(pts
				(xy -2.0828 3.3401) (xy 2.0828 3.3401) (xy 2.0828 -3.3401) (xy -2.0828 -3.3401)
			)
			(stroke
				(width 0)
				(type default)
			)
			(fill no)
			(layer "F.CrtYd")
		)
		(fp_poly
			(pts
				(xy -2.0828 3.3401) (xy 2.0828 3.3401) (xy 2.0828 -3.3401) (xy -2.0828 -3.3401)
			)
			(stroke
				(width 0)
				(type default)
			)
			(fill no)
			(layer "F.Fab")
		)
		(pad "1" smd rect
			(at -0.99949 2.0701 180)
			(size 0.3048 1.524)
			(layers "F.Cu" "F.Mask" "F.Paste")
			(net "P12VU_2490_EN_2")
		)
		(pad "2" smd rect
			(at -0.50038 2.0701 180)
			(size 0.3048 1.524)
			(layers "F.Cu" "F.Mask" "F.Paste")
			(net "P12VU_2490_VREF")
		)
		(pad "3" smd rect
			(at 0 2.0701 180)
			(size 0.3048 1.524)
			(layers "F.Cu" "F.Mask" "F.Paste")
			(net "P12VU_2490_PROG")
		)
		(pad "4" smd rect
			(at 0.50038 2.0701 180)
			(size 0.3048 1.524)
			(layers "F.Cu" "F.Mask" "F.Paste")
			(net "P12VU_2490_TIMER")
		)
		(pad "5" smd rect
			(at 0.99949 2.0701 180)
			(size 0.3048 1.524)
			(layers "F.Cu" "F.Mask" "F.Paste")
			(net "GND")
		)
		(pad "6" smd rect
			(at 0.99949 -2.0701 180)
			(size 0.3048 1.524)
			(layers "F.Cu" "F.Mask" "F.Paste")
			(net "P12VU_2490_PG")
		)
		(pad "7" smd rect
			(at 0.50038 -2.0701 180)
			(size 0.3048 1.524)
			(layers "F.Cu" "F.Mask" "F.Paste")
			(net "P12VU")
		)
		(pad "8" smd rect
			(at 0 -2.0701 180)
			(size 0.3048 1.524)
			(layers "F.Cu" "F.Mask" "F.Paste")
			(net "P12VU_2490_GATE")
		)
		(pad "9" smd rect
			(at -0.50038 -2.0701 180)
			(size 0.3048 1.524)
			(layers "F.Cu" "F.Mask" "F.Paste")
			(net "P12VU_2490_SENSE")
		)
		(pad "10" smd rect
			(at -0.99949 -2.0701 180)
			(size 0.3048 1.524)
			(layers "F.Cu" "F.Mask" "F.Paste")
			(net "P12VU_2490_VCC")
		)
	)
	(footprint ""
		(layer "F.Cu")
		(at 18.0594 -262.1534 90)
		(property "Reference" "D5"
			(at 0 0 90)
			(layer "F.SilkS")
			(hide yes)
			(effects
				(font
					(size 1.27 1.27)
				)
			)
		)
		(property "Value" "BAS16H-GP"
			(at 0 -5.5372 90)
			(unlocked yes)
			(layer "F.Fab")
			(hide yes)
			(effects
				(font
					(size 1.016 1.016)
					(thickness 0.1524)
				)
			)
		)
		(property "Device Type" "SOD123AKH48"
			(at 0 -7.0612 90)
			(unlocked yes)
			(layer "F.Fab")
			(hide yes)
			(effects
				(font
					(size 1.016 1.016)
					(thickness 0.1524)
				)
			)
		)
		(duplicate_pad_numbers_are_jumpers no)
		(fp_line
			(start 1.016 -2.667)
			(end -1.016 -2.667)
			(stroke
				(width 0.1524)
				(type default)
			)
			(layer "F.SilkS")
		)
		(fp_line
			(start -1.016 -2.667)
			(end -1.016 2.667)
			(stroke
				(width 0.1524)
				(type default)
			)
			(layer "F.SilkS")
		)
		(fp_line
			(start 1.016 2.667)
			(end 1.016 -2.667)
			(stroke
				(width 0.1524)
				(type default)
			)
			(layer "F.SilkS")
		)
		(fp_line
			(start -1.016 2.667)
			(end 1.016 2.667)
			(stroke
				(width 0.1524)
				(type default)
			)
			(layer "F.SilkS")
		)
		(fp_line
			(start 0.889 2.921)
			(end -0.889 2.921)
			(stroke
				(width 0.508)
				(type default)
			)
			(layer "F.SilkS")
		)
		(fp_rect
			(start -1.143 3.175)
			(end 1.143 -2.794)
			(stroke
				(width 0)
				(type default)
			)
			(fill no)
			(layer "F.CrtYd")
		)
		(fp_poly
			(pts
				(xy -1.143 -2.794) (xy 1.143 -2.794) (xy 1.143 3.175) (xy -1.143 3.175)
			)
			(stroke
				(width 0)
				(type default)
			)
			(fill no)
			(layer "F.Fab")
		)
		(pad "A" smd rect
			(at 0 -1.6891 90)
			(size 0.889 1.397)
			(layers "F.Cu" "F.Mask" "F.Paste")
			(net "FAN_TACH6")
		)
		(pad "K" smd rect
			(at 0 1.6891 90)
			(size 0.889 1.397)
			(layers "F.Cu" "F.Mask" "F.Paste")
			(net "P12V")
		)
	)
	(footprint ""
		(layer "F.Cu")
		(at 14.8844 -46.5582 -90)
		(property "Reference" "R174"
			(at 0 0 270)
			(layer "F.SilkS")
			(hide yes)
			(effects
				(font
					(size 1.27 1.27)
				)
			)
		)
		(property "Value" "0R2J-2-GP"
			(at 0.064008 -3.993896 270)
			(unlocked yes)
			(layer "F.Fab")
			(hide yes)
			(effects
				(font
					(size 1.016 1.016)
					(thickness 0.1524)
				)
			)
		)
		(property "Device Type" "R402H16"
			(at 0.064008 -5.517896 270)
			(unlocked yes)
			(layer "F.Fab")
			(hide yes)
			(effects
				(font
					(size 1.016 1.016)
					(thickness 0.1524)
				)
			)
		)
		(duplicate_pad_numbers_are_jumpers no)
		(fp_line
			(start -0.508 -0.9398)
			(end -0.508 0.9398)
			(stroke
				(width 0.1524)
				(type default)
			)
			(layer "F.SilkS")
		)
		(fp_line
			(start 0.508 -0.9398)
			(end -0.508 -0.9398)
			(stroke
				(width 0.1524)
				(type default)
			)
			(layer "F.SilkS")
		)
		(fp_rect
			(start -0.508 0.9398)
			(end 0.508 -0.9398)
			(stroke
				(width 0)
				(type default)
			)
			(fill no)
			(layer "F.CrtYd")
		)
		(fp_rect
			(start -0.508 0.9398)
			(end 0.508 -0.9398)
			(stroke
				(width 0)
				(type default)
			)
			(fill no)
			(layer "F.Fab")
		)
		(pad "1" smd custom
			(at 0 -0.4445 270)
			(size 0.1397 0.1397)
			(layers "F.Cu" "F.Mask" "F.Paste")
			(net "SELF_2A_HB")
			(options
				(clearance outline)
				(anchor circle)
			)
			(primitives
				(gr_poly
					(pts
						(arc
							(start -0.1778 -0.2794)
							(mid -0.249642 -0.249642)
							(end -0.2794 -0.1778)
						)
						(arc
							(start -0.2794 0.1778)
							(mid -0.249642 0.249642)
							(end -0.1778 0.2794)
						)
						(arc
							(start 0.1778 0.2794)
							(mid 0.249642 0.249642)
							(end 0.2794 0.1778)
						)
						(arc
							(start 0.2794 -0.1778)
							(mid 0.249642 -0.249642)
							(end 0.1778 -0.2794)
						)
					)
					(width 0)
					(fill yes)
				)
			)
		)
		(pad "2" smd custom
			(at 0 0.4445 270)
			(size 0.1397 0.1397)
			(layers "F.Cu" "F.Mask" "F.Paste")
			(net "SEB_PEER_1A_HB")
			(options
				(clearance outline)
				(anchor circle)
			)
			(primitives
				(gr_poly
					(pts
						(arc
							(start -0.1778 -0.2794)
							(mid -0.249642 -0.249642)
							(end -0.2794 -0.1778)
						)
						(arc
							(start -0.2794 0.1778)
							(mid -0.249642 0.249642)
							(end -0.1778 0.2794)
						)
						(arc
							(start 0.1778 0.2794)
							(mid 0.249642 0.249642)
							(end 0.2794 0.1778)
						)
						(arc
							(start 0.2794 -0.1778)
							(mid 0.249642 -0.249642)
							(end 0.1778 -0.2794)
						)
					)
					(width 0)
					(fill yes)
				)
			)
		)
	)
	(footprint ""
		(layer "F.Cu")
		(at 14.7574 -262.2804 180)
		(property "Reference" "C35"
			(at 0 0 180)
			(layer "F.SilkS")
			(hide yes)
			(effects
				(font
					(size 1.27 1.27)
				)
			)
		)
		(property "Value" "SCD1U16V2KX-3GP"
			(at 1.1811 -2.7051 180)
			(unlocked yes)
			(layer "F.Fab")
			(hide yes)
			(effects
				(font
					(size 1.016 1.016)
					(thickness 0.1524)
				)
			)
		)
		(property "Device Type" "C402H22"
			(at 1.1811 -4.2291 180)
			(unlocked yes)
			(layer "F.Fab")
			(hide yes)
			(effects
				(font
					(size 1.016 1.016)
					(thickness 0.1524)
				)
			)
		)
		(duplicate_pad_numbers_are_jumpers no)
		(fp_rect
			(start -0.4318 0.9525)
			(end 0.4318 -0.9525)
			(stroke
				(width 0)
				(type default)
			)
			(fill no)
			(layer "F.CrtYd")
		)
		(fp_rect
			(start -0.4318 0.9525)
			(end 0.4318 -0.9525)
			(stroke
				(width 0)
				(type default)
			)
			(fill no)
			(layer "F.Fab")
		)
		(pad "1" smd custom
			(at 0 -0.4445 180)
			(size 0.1524 0.1524)
			(layers "F.Cu" "F.Mask" "F.Paste")
			(net "FAN_TACH6")
			(options
				(clearance outline)
				(anchor circle)
			)
			(primitives
				(gr_poly
					(pts
						(arc
							(start 0.3048 -0.2032)
							(mid 0.275042 -0.275042)
							(end 0.2032 -0.3048)
						)
						(arc
							(start -0.2032 -0.3048)
							(mid -0.275042 -0.275042)
							(end -0.3048 -0.2032)
						)
						(arc
							(start -0.3048 0.2032)
							(mid -0.275042 0.275042)
							(end -0.2032 0.3048)
						)
						(arc
							(start 0.2032 0.3048)
							(mid 0.275042 0.275042)
							(end 0.3048 0.2032)
						)
					)
					(width 0)
					(fill yes)
				)
			)
		)
		(pad "2" smd custom
			(at 0 0.4445 180)
			(size 0.1524 0.1524)
			(layers "F.Cu" "F.Mask" "F.Paste")
			(net "GND")
			(options
				(clearance outline)
				(anchor circle)
			)
			(primitives
				(gr_poly
					(pts
						(arc
							(start 0.3048 -0.2032)
							(mid 0.275042 -0.275042)
							(end 0.2032 -0.3048)
						)
						(arc
							(start -0.2032 -0.3048)
							(mid -0.275042 -0.275042)
							(end -0.3048 -0.2032)
						)
						(arc
							(start -0.3048 0.2032)
							(mid -0.275042 0.275042)
							(end -0.2032 0.3048)
						)
						(arc
							(start 0.2032 0.3048)
							(mid 0.275042 0.275042)
							(end 0.3048 0.2032)
						)
					)
					(width 0)
					(fill yes)
				)
			)
		)
	)
	(footprint ""
		(layer "F.Cu")
		(at 8.9662 -106.2482 -90)
		(property "Reference" "TC2"
			(at 0 0 270)
			(layer "F.SilkS")
			(hide yes)
			(effects
				(font
					(size 1.27 1.27)
				)
			)
		)
		(property "Value" "ST68U16VDM-1-GP"
			(at 0 -9.6012 270)
			(unlocked yes)
			(layer "F.Fab")
			(hide yes)
			(effects
				(font
					(size 1.016 1.016)
					(thickness 0.1524)
				)
			)
		)
		(property "Device Type" "CT7343H79"
			(at 0 -11.1252 270)
			(unlocked yes)
			(layer "F.Fab")
			(hide yes)
			(effects
				(font
					(size 1.016 1.016)
					(thickness 0.1524)
				)
			)
		)
		(duplicate_pad_numbers_are_jumpers no)
		(fp_line
			(start -2.286 4.8768)
			(end -2.286 2.032)
			(stroke
				(width 0.1524)
				(type default)
			)
			(layer "F.SilkS")
		)
		(fp_line
			(start 2.286 4.8768)
			(end -2.286 4.8768)
			(stroke
				(width 0.1524)
				(type default)
			)
			(layer "F.SilkS")
		)
		(fp_line
			(start 2.286 2.032)
			(end 2.286 4.8768)
			(stroke
				(width 0.1524)
				(type default)
			)
			(layer "F.SilkS")
		)
		(fp_line
			(start 2.286 -2.032)
			(end 2.286 -4.8768)
			(stroke
				(width 0.1524)
				(type default)
			)
			(layer "F.SilkS")
		)
		(fp_line
			(start 2.1082 -4.699)
			(end -2.1082 -4.699)
			(stroke
				(width 0.508)
				(type default)
			)
			(layer "F.SilkS")
		)
		(fp_line
			(start -2.286 -4.8768)
			(end -2.286 -2.032)
			(stroke
				(width 0.1524)
				(type default)
			)
			(layer "F.SilkS")
		)
		(fp_line
			(start 2.286 -4.8768)
			(end -2.286 -4.8768)
			(stroke
				(width 0.1524)
				(type default)
			)
			(layer "F.SilkS")
		)
		(fp_rect
			(start -2.1463 3.6449)
			(end 2.1463 -3.6449)
			(stroke
				(width 0)
				(type default)
			)
			(fill no)
			(layer "F.CrtYd")
		)
		(fp_poly
			(pts
				(xy -2.54 4.953) (xy -2.54 4.2926) (xy -3.81 4.2926) (xy -3.81 -4.2926) (xy -2.54 -4.2926) (xy -2.54 -4.953)
				(xy 2.54 -4.953) (xy 2.54 -4.2926) (xy 3.81 -4.2926) (xy 3.81 -1.6256) (xy 2.1463 -1.6256) (xy 2.1463 -3.6449)
				(xy -2.1463 -3.6449) (xy -2.1463 3.6449) (xy 2.1463 3.6449) (xy 2.1463 -1.6129) (xy 3.81 -1.6129)
				(xy 3.81 4.2926) (xy 2.54 4.2926) (xy 2.54 4.953)
			)
			(stroke
				(width 0)
				(type default)
			)
			(fill no)
			(layer "F.CrtYd")
		)
		(fp_rect
			(start -2.54 4.953)
			(end 2.54 -4.953)
			(stroke
				(width 0)
				(type default)
			)
			(fill no)
			(layer "F.Fab")
		)
		(fp_rect
			(start -3.81 4.2926)
			(end -2.54 -4.2926)
			(stroke
				(width 0)
				(type default)
			)
			(fill no)
			(layer "F.Fab")
		)
		(fp_rect
			(start 2.54 4.2926)
			(end 3.81 -4.2926)
			(stroke
				(width 0)
				(type default)
			)
			(fill no)
			(layer "F.Fab")
		)
		(pad "1" smd rect
			(at 0 -3.1496 270)
			(size 2.413 2.286)
			(layers "F.Cu" "F.Mask" "F.Paste")
			(net "P12VU")
		)
		(pad "2" smd rect
			(at 0 3.1496 270)
			(size 2.413 2.286)
			(layers "F.Cu" "F.Mask" "F.Paste")
			(net "GND")
		)
		(zone
			(layer "F.Cu")
			(hatch none 0.5)
			(connect_pads
				(clearance 0)
			)
			(min_thickness 0.25)
			(keepout
				(tracks allowed)
				(vias not_allowed)
				(pads allowed)
				(copperpour not_allowed)
				(footprints allowed)
			)
			(placement
				(enabled no)
				(sheetname "")
			)
			(fill
				(thermal_gap 0.5)
				(thermal_bridge_width 0.5)
				(island_removal_mode 0)
			)
			(polygon
				(pts
					(xy 4.3688 -107.7595) (xy 4.3688 -104.7369) (xy 7.2644 -104.7369) (xy 7.5946 -104.7369) (xy 7.5946 -107.7595)
					(xy 7.2644 -107.7595)
				)
			)
		)
		(zone
			(layer "F.Cu")
			(hatch none 0.5)
			(connect_pads
				(clearance 0)
			)
			(min_thickness 0.25)
			(keepout
				(tracks allowed)
				(vias not_allowed)
				(pads allowed)
				(copperpour not_allowed)
				(footprints allowed)
			)
			(placement
				(enabled no)
				(sheetname "")
			)
			(fill
				(thermal_gap 0.5)
				(thermal_bridge_width 0.5)
				(island_removal_mode 0)
			)
			(polygon
				(pts
					(xy 10.6553 -104.7369) (xy 13.5636 -104.7369) (xy 13.5636 -107.7595) (xy 10.668 -107.7595) (xy 10.3378 -107.7595)
					(xy 10.3378 -104.7369)
				)
			)
		)
	)
)
